FILE_TYPE = CONNECTIVITY;
{Allegro Design Entry HDL 17.4-2019 S026 (4007227) 1/17/2022}
"PAGE_NUMBER" = 404;
0"NC";
1"P5E_CPU0_P1_TX_C_DN<15:8>";
2"P5E_CPU0_P1_TX_C_DP<15:8>";
3"P5E_CPU0_P1_TX_C_DP<7:0>";
4"P5E_CPU0_P1_TX_C_DN<7:0>";
5"P5E_CPU0_P1_TX_C_DN<6>";
6"P5E_CPU0_P1_TX_C_DP<2>";
7"P5E_CPU0_P1_TX_C_DN<1>";
8"P5E_CPU0_P1_TX_C_DN<4>";
9"P5E_CPU0_P1_TX_C_DN<3>";
10"P5E_CPU0_P1_TX_C_DN<5>";
11"P5E_CPU0_P1_TX_C_DN<0>";
12"P5E_CPU0_P1_TX_C_DN<7>";
13"P5E_CPU0_P1_TX_C_DN<2>";
14"P5E_CPU0_P1_TX_C_DP<12>";
15"P5E_CPU0_P1_TX_C_DP<1>";
16"P5E_CPU0_P1_TX_C_DP<3>";
17"P5E_CPU0_P1_TX_C_DP<6>";
18"P5E_CPU0_P1_TX_C_DP<5>";
19"P5E_CPU0_P1_TX_C_DP<4>";
20"P5E_CPU0_P1_TX_C_DP<7>";
21"P5E_CPU0_P1_TX_C_DP<0>";
22"P5E_CPU0_P1_TX_C_DP<11>";
23"P5E_CPU0_P1_TX_C_DP<8>";
24"P5E_CPU0_P1_TX_C_DP<9>";
25"P5E_CPU0_P1_TX_C_DN<13>";
26"P5E_CPU0_P1_TX_C_DN<12>";
27"P5E_CPU0_P1_TX_C_DN<15>";
28"P5E_CPU0_P1_TX_C_DN<11>";
29"P5E_CPU0_P1_TX_C_DN<10>";
30"P5E_CPU0_P1_TX_C_DN<8>";
31"P5E_CPU0_P1_TX_C_DN<9>";
32"P5E_CPU0_P1_TX_C_DP<10>";
33"P5E_CPU0_P1_TX_C_DP<13>";
34"P5E_CPU0_P1_TX_C_DP<15>";
35"P5E_CPU0_P1_TX_C_DP<14>";
36"P5E_CPU0_P1_TX_C_DN<14>";
%"PT5161LRS"
"8","(-7875,3900)","0","pure_quanta","I1";
;
LOCATION"U6011"
$SEC"8"
CDS_SEC"8"
PART_TYPE"SMLF"
VALUE"PT5161LRS"
MATERIAL"IC"
CDS_LIB"pure_quanta"
CDS_LMAN_SYM_OUTLINE"-350,1450,300,-1400"
NEEDS_NO_SIZE"TRUE"
PART_NUMBER"AJ051610U03";
"B_PERN7"
$PN"CD35"23;
"B_PERP7"
$PN"CB34"30;
"B_PERN6"
$PN"BU35"24;
"B_PERP6"
$PN"BR34"31;
"B_PERN5"
$PN"BK35"32;
"B_PERP5"
$PN"BH34"29;
"B_PERN4"
$PN"BC35"22;
"B_PERP4"
$PN"BA34"28;
"B_PERN3"
$PN"AT35"14;
"B_PERP3"
$PN"AP34"26;
"B_PERN2"
$PN"AJ35"33;
"B_PERP2"
$PN"AG34"25;
"B_PERN1"
$PN"AB35"36;
"B_PERP1"
$PN"Y34"35;
"B_PERN0"
$PN"R35"34;
"B_PERP0"
$PN"N34"27;
%"TAP"
"1","(-6850,4100)","0","standard","I10";
;
CDS_LIB"standard"
BODY_TYPE"PLUMBING"
HDL_TAP"TRUE";
"B \NAC \NWC"1;
"S \NAC"
BN"12"26;
%"TAP"
"1","(-6650,4000)","0","standard","I11";
;
CDS_LIB"standard"
BODY_TYPE"PLUMBING"
HDL_TAP"TRUE";
"B \NAC \NWC"2;
"S \NAC"
BN"12"14;
%"TAP"
"1","(-6850,4450)","0","standard","I12";
;
CDS_LIB"standard"
BODY_TYPE"PLUMBING"
HDL_TAP"TRUE";
"B \NAC \NWC"1;
"S \NAC"
BN"13"25;
%"TAP"
"1","(-6650,4350)","0","standard","I13";
;
CDS_LIB"standard"
BODY_TYPE"PLUMBING"
HDL_TAP"TRUE";
"B \NAC \NWC"2;
"S \NAC"
BN"13"33;
%"TAP"
"1","(-6650,4800)","0","standard","I14";
;
CDS_LIB"standard"
BODY_TYPE"PLUMBING"
HDL_TAP"TRUE";
"B \NAC \NWC"2;
"S \NAC"
BN"14"35;
%"TAP"
"1","(-6850,4700)","0","standard","I15";
;
CDS_LIB"standard"
BODY_TYPE"PLUMBING"
HDL_TAP"TRUE";
"B \NAC \NWC"1;
"S \NAC"
BN"14"36;
%"TAP"
"1","(-6850,5150)","0","standard","I16";
;
CDS_LIB"standard"
BODY_TYPE"PLUMBING"
HDL_TAP"TRUE";
"B \NAC \NWC"1;
"S \NAC"
BN"15"27;
%"TAP"
"1","(-6650,5050)","0","standard","I17";
;
CDS_LIB"standard"
BODY_TYPE"PLUMBING"
HDL_TAP"TRUE";
"B \NAC \NWC"2;
"S \NAC"
BN"15"34;
%"TAP"
"1","(-6650,2600)","0","standard","I2";
;
CDS_LIB"standard"
BODY_TYPE"PLUMBING"
HDL_TAP"TRUE";
"B \NAC \NWC"2;
"S \NAC"
BN"8"23;
%"TAP"
"1","(-2225,2650)","0","standard","I20";
;
CDS_LIB"standard"
BODY_TYPE"PLUMBING"
HDL_TAP"TRUE";
"B \NAC \NWC"4;
"S \NAC"
BN"0"11;
%"TAP"
"1","(-2025,2550)","0","standard","I21";
;
CDS_LIB"standard"
BODY_TYPE"PLUMBING"
HDL_TAP"TRUE";
"B \NAC \NWC"3;
"S \NAC"
BN"0"21;
%"TAP"
"1","(-2225,2900)","0","standard","I22";
;
CDS_LIB"standard"
BODY_TYPE"PLUMBING"
HDL_TAP"TRUE";
"B \NAC \NWC"4;
"S \NAC"
BN"1"7;
%"TAP"
"1","(-2025,3000)","0","standard","I23";
;
CDS_LIB"standard"
BODY_TYPE"PLUMBING"
HDL_TAP"TRUE";
"B \NAC \NWC"3;
"S \NAC"
BN"1"15;
%"TAP"
"1","(-2225,3350)","0","standard","I24";
;
CDS_LIB"standard"
BODY_TYPE"PLUMBING"
HDL_TAP"TRUE";
"B \NAC \NWC"4;
"S \NAC"
BN"2"13;
%"TAP"
"1","(-2225,3700)","0","standard","I25";
;
CDS_LIB"standard"
BODY_TYPE"PLUMBING"
HDL_TAP"TRUE";
"B \NAC \NWC"4;
"S \NAC"
BN"3"9;
%"TAP"
"1","(-2025,3250)","0","standard","I26";
;
CDS_LIB"standard"
BODY_TYPE"PLUMBING"
HDL_TAP"TRUE";
"B \NAC \NWC"3;
"S \NAC"
BN"2"6;
%"TAP"
"1","(-2025,3600)","0","standard","I27";
;
CDS_LIB"standard"
BODY_TYPE"PLUMBING"
HDL_TAP"TRUE";
"B \NAC \NWC"3;
"S \NAC"
BN"3"16;
%"TAP"
"1","(-2225,4050)","0","standard","I28";
;
CDS_LIB"standard"
BODY_TYPE"PLUMBING"
HDL_TAP"TRUE";
"B \NAC \NWC"4;
"S \NAC"
BN"4"8;
%"TAP"
"1","(-2025,3950)","0","standard","I29";
;
CDS_LIB"standard"
BODY_TYPE"PLUMBING"
HDL_TAP"TRUE";
"B \NAC \NWC"3;
"S \NAC"
BN"4"19;
%"TAP"
"1","(-6850,2700)","0","standard","I3";
;
CDS_LIB"standard"
BODY_TYPE"PLUMBING"
HDL_TAP"TRUE";
"B \NAC \NWC"1;
"S \NAC"
BN"8"30;
%"TAP"
"1","(-2225,4400)","0","standard","I30";
;
CDS_LIB"standard"
BODY_TYPE"PLUMBING"
HDL_TAP"TRUE";
"B \NAC \NWC"4;
"S \NAC"
BN"5"10;
%"TAP"
"1","(-2025,4300)","0","standard","I31";
;
CDS_LIB"standard"
BODY_TYPE"PLUMBING"
HDL_TAP"TRUE";
"B \NAC \NWC"3;
"S \NAC"
BN"5"18;
%"TAP"
"1","(-2025,4650)","0","standard","I32";
;
CDS_LIB"standard"
BODY_TYPE"PLUMBING"
HDL_TAP"TRUE";
"B \NAC \NWC"3;
"S \NAC"
BN"6"17;
%"TAP"
"1","(-2225,4750)","0","standard","I33";
;
CDS_LIB"standard"
BODY_TYPE"PLUMBING"
HDL_TAP"TRUE";
"B \NAC \NWC"4;
"S \NAC"
BN"6"5;
%"TAP"
"1","(-2225,5100)","0","standard","I34";
;
CDS_LIB"standard"
BODY_TYPE"PLUMBING"
HDL_TAP"TRUE";
"B \NAC \NWC"4;
"S \NAC"
BN"7"12;
%"TAP"
"1","(-2025,5000)","0","standard","I35";
;
CDS_LIB"standard"
BODY_TYPE"PLUMBING"
HDL_TAP"TRUE";
"B \NAC \NWC"3;
"S \NAC"
BN"7"20;
%"PT5161LRS"
"9","(-3250,3850)","0","pure_quanta","I38";
;
LOCATION"U6011"
$SEC"9"
CDS_SEC"9"
MATERIAL"IC"
VALUE"PT5161LRS"
PART_TYPE"SMLF"
NEEDS_NO_SIZE"TRUE"
CDS_LMAN_SYM_OUTLINE"-350,1450,300,-1400"
CDS_LIB"pure_quanta"
PART_NUMBER"AJ051610U03";
"B_PERN15"
$PN"EY35"21;
"B_PERP15"
$PN"EV34"11;
"B_PERN14"
$PN"EN35"7;
"B_PERP14"
$PN"EL34"15;
"B_PERN13"
$PN"EF35"6;
"B_PERP13"
$PN"ED34"13;
"B_PERN12"
$PN"DW35"16;
"B_PERP12"
$PN"DU34"9;
"B_PERN11"
$PN"DM35"19;
"B_PERP11"
$PN"DK34"8;
"B_PERN10"
$PN"DE35"18;
"B_PERP10"
$PN"DC34"10;
"B_PERN9"
$PN"CV35"17;
"B_PERP9"
$PN"CT34"5;
"B_PERN8"
$PN"CL35"20;
"B_PERP8"
$PN"CJ34"12;
%"TAP"
"1","(-6850,3050)","0","standard","I4";
;
CDS_LIB"standard"
BODY_TYPE"PLUMBING"
HDL_TAP"TRUE";
"B \NAC \NWC"1;
"S \NAC"
BN"9"31;
%"TAP"
"1","(-6650,2950)","0","standard","I5";
;
CDS_LIB"standard"
BODY_TYPE"PLUMBING"
HDL_TAP"TRUE";
"B \NAC \NWC"2;
"S \NAC"
BN"9"24;
%"TAP"
"1","(-6850,3400)","0","standard","I6";
;
CDS_LIB"standard"
BODY_TYPE"PLUMBING"
HDL_TAP"TRUE";
"B \NAC \NWC"1;
"S \NAC"
BN"10"29;
%"TAP"
"1","(-6650,3300)","0","standard","I7";
;
CDS_LIB"standard"
BODY_TYPE"PLUMBING"
HDL_TAP"TRUE";
"B \NAC \NWC"2;
"S \NAC"
BN"10"32;
%"TAP"
"1","(-6650,3650)","0","standard","I8";
;
CDS_LIB"standard"
BODY_TYPE"PLUMBING"
HDL_TAP"TRUE";
"B \NAC \NWC"2;
"S \NAC"
BN"11"22;
%"TAP"
"1","(-6850,3750)","0","standard","I9";
;
CDS_LIB"standard"
BODY_TYPE"PLUMBING"
HDL_TAP"TRUE";
"B \NAC \NWC"1;
"S \NAC"
BN"11"28;
END.
